FILE_TYPE=LIBRARY_PARTS;
primitive 'PCA9539RPW';
  pin
    'INT':
      PIN_NUMBER='(1)';
      BIDIRECTIONAL='TRUE';
      INPUT_LOAD='(-0.01,0.01)';
      OUTPUT_LOAD='(1.0,-1.0)';
    'A1':
      PIN_NUMBER='(2)';
      INPUT_LOAD='(-0.01,0.01)';
    'RESET':
      PIN_NUMBER='(3)';
      BIDIRECTIONAL='TRUE';
      INPUT_LOAD='(-0.01,0.01)';
      OUTPUT_LOAD='(1.0,-1.0)';
    'IO0_0':
      PIN_NUMBER='(4)';
      BIDIRECTIONAL='TRUE';
      INPUT_LOAD='(-0.01,0.01)';
      OUTPUT_LOAD='(1.0,-1.0)';
    'IO0_1':
      PIN_NUMBER='(5)';
      BIDIRECTIONAL='TRUE';
      INPUT_LOAD='(-0.01,0.01)';
      OUTPUT_LOAD='(1.0,-1.0)';
    'IO0_2':
      PIN_NUMBER='(6)';
      BIDIRECTIONAL='TRUE';
      INPUT_LOAD='(-0.01,0.01)';
      OUTPUT_LOAD='(1.0,-1.0)';
    'IO0_3':
      PIN_NUMBER='(7)';
      BIDIRECTIONAL='TRUE';
      INPUT_LOAD='(-0.01,0.01)';
      OUTPUT_LOAD='(1.0,-1.0)';
    'IO0_4':
      PIN_NUMBER='(8)';
      BIDIRECTIONAL='TRUE';
      INPUT_LOAD='(-0.01,0.01)';
      OUTPUT_LOAD='(1.0,-1.0)';
    'IO0_5':
      PIN_NUMBER='(9)';
      BIDIRECTIONAL='TRUE';
      INPUT_LOAD='(-0.01,0.01)';
      OUTPUT_LOAD='(1.0,-1.0)';
    'IO0_6':
      PIN_NUMBER='(10)';
      BIDIRECTIONAL='TRUE';
      INPUT_LOAD='(-0.01,0.01)';
      OUTPUT_LOAD='(1.0,-1.0)';
    'IO0_7':
      PIN_NUMBER='(11)';
      BIDIRECTIONAL='TRUE';
      INPUT_LOAD='(-0.01,0.01)';
      OUTPUT_LOAD='(1.0,-1.0)';
    'VSS':
      PIN_NUMBER='(12)';
      PINUSE='POWER';
      NO_LOAD_CHECK='Both';
      NO_IO_CHECK='Both';
      NO_ASSERT_CHECK='TRUE';
      NO_DIR_CHECK='TRUE';
      ALLOW_CONNECT='TRUE';
    'IO1_0':
      PIN_NUMBER='(13)';
      BIDIRECTIONAL='TRUE';
      INPUT_LOAD='(-0.01,0.01)';
      OUTPUT_LOAD='(1.0,-1.0)';
    'IO1_1':
      PIN_NUMBER='(14)';
      BIDIRECTIONAL='TRUE';
      INPUT_LOAD='(-0.01,0.01)';
      OUTPUT_LOAD='(1.0,-1.0)';
    'IO1_2':
      PIN_NUMBER='(15)';
      BIDIRECTIONAL='TRUE';
      INPUT_LOAD='(-0.01,0.01)';
      OUTPUT_LOAD='(1.0,-1.0)';
    'IO1_3':
      PIN_NUMBER='(16)';
      BIDIRECTIONAL='TRUE';
      INPUT_LOAD='(-0.01,0.01)';
      OUTPUT_LOAD='(1.0,-1.0)';
    'IO1_4':
      PIN_NUMBER='(17)';
      BIDIRECTIONAL='TRUE';
      INPUT_LOAD='(-0.01,0.01)';
      OUTPUT_LOAD='(1.0,-1.0)';
    'IO1_5':
      PIN_NUMBER='(18)';
      BIDIRECTIONAL='TRUE';
      INPUT_LOAD='(-0.01,0.01)';
      OUTPUT_LOAD='(1.0,-1.0)';
    'IO1_6':
      PIN_NUMBER='(19)';
      BIDIRECTIONAL='TRUE';
      INPUT_LOAD='(-0.01,0.01)';
      OUTPUT_LOAD='(1.0,-1.0)';
    'IO1_7':
      PIN_NUMBER='(20)';
      BIDIRECTIONAL='TRUE';
      INPUT_LOAD='(-0.01,0.01)';
      OUTPUT_LOAD='(1.0,-1.0)';
    'A0':
      PIN_NUMBER='(21)';
      INPUT_LOAD='(-0.01,0.01)';
    'SCL':
      PIN_NUMBER='(22)';
      BIDIRECTIONAL='TRUE';
      INPUT_LOAD='(-0.01,0.01)';
      OUTPUT_LOAD='(1.0,-1.0)';
    'SDA':
      PIN_NUMBER='(23)';
      BIDIRECTIONAL='TRUE';
      INPUT_LOAD='(-0.01,0.01)';
      OUTPUT_LOAD='(1.0,-1.0)';
    'VDD':
      PIN_NUMBER='(24)';
      PINUSE='POWER';
      NO_LOAD_CHECK='Both';
      NO_IO_CHECK='Both';
      NO_ASSERT_CHECK='TRUE';
      NO_DIR_CHECK='TRUE';
      ALLOW_CONNECT='TRUE';
  end_pin;
  body
    PART_NAME='PCA9539RPW';
    BODY_NAME='PCA9539RPW';
    PHYS_DES_PREFIX='U';
    CLASS='IC';
  end_body;
end_primitive;

END.
